(kicad_pcb
	(version 20260206)
	(generator "pcbnew")
	(generator_version "10.0")
	(general
		(thickness 1.6)
		(legacy_teardrops no)
	)
	(paper "A4")
	(title_block
		(title "baseboard — 13948-1b.1110WZS1818.brd")
		(comment 1 "Honey Badger (Wiwynn) / footprints 2485-2493 of 2523")
	)
	(layers
		(0 "F.Cu" signal "TOP")
		(4 "In1.Cu" signal "L2GND")
		(6 "In2.Cu" signal "L3")
		(8 "In3.Cu" signal "L4VCC")
		(10 "In4.Cu" signal "L5VCC")
		(12 "In5.Cu" signal "L6")
		(14 "In6.Cu" signal "L7GND")
		(2 "B.Cu" signal "BOTTOM")
		(9 "F.Adhes" user "F.Adhesive")
		(11 "B.Adhes" user "B.Adhesive")
		(13 "F.Paste" user "Package Geometry/Pastemask Top")
		(15 "B.Paste" user "Package Geometry/Pastemask Bottom")
		(5 "F.SilkS" user "Ref Des/Silkscreen Top")
		(7 "B.SilkS" user "Ref Des/Silkscreen Bottom")
		(1 "F.Mask" user "Board Geometry/Soldermask Top")
		(3 "B.Mask" user "Board Geometry/Soldermask Bottom")
		(17 "Dwgs.User" user "User.Drawings")
		(19 "Cmts.User" user "User.Comments")
		(21 "Eco1.User" user "User.Eco1")
		(23 "Eco2.User" user "User.Eco2")
		(25 "Edge.Cuts" user "Board Geometry/Outline")
		(27 "Margin" user)
		(31 "F.CrtYd" user "Package Geometry/Place Bound Top")
		(29 "B.CrtYd" user "Package Geometry/Place Bound Bottom")
		(35 "F.Fab" user "Ref Des/Assembly Top")
		(33 "B.Fab" user "Ref Des/Assembly Bottom")
	)
	(footprint ""
		(layer "B.Cu")
		(at 110.725966 -43.39844 -90)
		(property "Reference" "SC988"
			(at 0 0 90)
			(layer "B.SilkS")
			(hide yes)
			(effects
				(font
					(size 1.27 1.27)
				)
				(justify mirror)
			)
		)
		(property "Value" "SCD1U16V2KX-3GP"
			(at -1.1811 -2.7051 270)
			(unlocked yes)
			(layer "B.Fab")
			(hide yes)
			(effects
				(font
					(size 1.016 1.016)
					(thickness 0.1524)
				)
				(justify mirror)
			)
		)
		(property "Device Type" "C402H22"
			(at -1.1811 -4.2291 270)
			(unlocked yes)
			(layer "B.Fab")
			(hide yes)
			(effects
				(font
					(size 1.016 1.016)
					(thickness 0.1524)
				)
				(justify mirror)
			)
		)
		(duplicate_pad_numbers_are_jumpers no)
		(fp_rect
			(start 0.4318 0.9525)
			(end -0.4318 -0.9525)
			(stroke
				(width 0)
				(type default)
			)
			(fill no)
			(layer "B.CrtYd")
		)
		(fp_rect
			(start 0.4318 0.9525)
			(end -0.4318 -0.9525)
			(stroke
				(width 0)
				(type default)
			)
			(fill no)
			(layer "B.Fab")
		)
		(pad "1" smd custom
			(at 0 -0.4445 90)
			(size 0.1524 0.1524)
			(layers "B.Cu" "B.Mask" "B.Paste")
			(net "P1V8_C")
			(options
				(clearance outline)
				(anchor circle)
			)
			(primitives
				(gr_poly
					(pts
						(arc
							(start 0.3048 0.2032)
							(mid 0.275042 0.275042)
							(end 0.2032 0.3048)
						)
						(arc
							(start -0.2032 0.3048)
							(mid -0.275042 0.275042)
							(end -0.3048 0.2032)
						)
						(arc
							(start -0.3048 -0.2032)
							(mid -0.275042 -0.275042)
							(end -0.2032 -0.3048)
						)
						(arc
							(start 0.2032 -0.3048)
							(mid 0.275042 -0.275042)
							(end 0.3048 -0.2032)
						)
					)
					(width 0)
					(fill yes)
				)
			)
		)
		(pad "2" smd custom
			(at 0 0.4445 90)
			(size 0.1524 0.1524)
			(layers "B.Cu" "B.Mask" "B.Paste")
			(net "GND")
			(options
				(clearance outline)
				(anchor circle)
			)
			(primitives
				(gr_poly
					(pts
						(arc
							(start 0.3048 0.2032)
							(mid 0.275042 0.275042)
							(end 0.2032 0.3048)
						)
						(arc
							(start -0.2032 0.3048)
							(mid -0.275042 0.275042)
							(end -0.3048 0.2032)
						)
						(arc
							(start -0.3048 -0.2032)
							(mid -0.275042 -0.275042)
							(end -0.2032 -0.3048)
						)
						(arc
							(start 0.2032 -0.3048)
							(mid 0.275042 -0.275042)
							(end 0.3048 -0.2032)
						)
					)
					(width 0)
					(fill yes)
				)
			)
		)
	)
	(footprint ""
		(layer "B.Cu")
		(at 118.894098 -76.890118 -90)
		(property "Reference" "SC1150"
			(at 0 0 90)
			(layer "B.SilkS")
			(hide yes)
			(effects
				(font
					(size 1.27 1.27)
				)
				(justify mirror)
			)
		)
		(property "Value" "SC22U6D3V5MX-2GP"
			(at 0.0762 -6.1214 270)
			(unlocked yes)
			(layer "B.Fab")
			(hide yes)
			(effects
				(font
					(size 1.016 1.016)
					(thickness 0.1524)
				)
				(justify mirror)
			)
		)
		(property "Device Type" "C805H58"
			(at 0.0762 -8.1534 270)
			(unlocked yes)
			(layer "B.Fab")
			(hide yes)
			(effects
				(font
					(size 1.016 1.016)
					(thickness 0.1524)
				)
				(justify mirror)
			)
		)
		(duplicate_pad_numbers_are_jumpers no)
		(fp_line
			(start -0.635 0)
			(end 0.635 0)
			(stroke
				(width 0.508)
				(type default)
			)
			(layer "B.SilkS")
		)
		(fp_rect
			(start 0.9652 1.778)
			(end -0.9652 -1.778)
			(stroke
				(width 0)
				(type default)
			)
			(fill no)
			(layer "B.CrtYd")
		)
		(fp_poly
			(pts
				(xy 0.9652 -1.778) (xy -0.9652 -1.778) (xy -0.9652 1.778) (xy 0.9652 1.778)
			)
			(stroke
				(width 0)
				(type default)
			)
			(fill no)
			(layer "B.Fab")
		)
		(pad "1" smd rect
			(at 0 -0.9652 90)
			(size 1.397 1.143)
			(layers "B.Cu" "B.Mask" "B.Paste")
			(net "XTAL_VDDA18")
		)
		(pad "2" smd rect
			(at 0 0.9652 90)
			(size 1.397 1.143)
			(layers "B.Cu" "B.Mask" "B.Paste")
			(net "GND")
		)
	)
	(footprint ""
		(layer "B.Cu")
		(at 101.962966 -51.054 180)
		(property "Reference" "SC1020"
			(at 0 0 0)
			(layer "B.SilkS")
			(hide yes)
			(effects
				(font
					(size 1.27 1.27)
				)
				(justify mirror)
			)
		)
		(property "Value" "SC10U6D3V5KX-4GP"
			(at 0.0762 -6.1214 180)
			(unlocked yes)
			(layer "B.Fab")
			(hide yes)
			(effects
				(font
					(size 1.016 1.016)
					(thickness 0.1524)
				)
				(justify mirror)
			)
		)
		(property "Device Type" "C805H58"
			(at 0.0762 -8.1534 180)
			(unlocked yes)
			(layer "B.Fab")
			(hide yes)
			(effects
				(font
					(size 1.016 1.016)
					(thickness 0.1524)
				)
				(justify mirror)
			)
		)
		(duplicate_pad_numbers_are_jumpers no)
		(fp_line
			(start -0.635 0)
			(end 0.635 0)
			(stroke
				(width 0.508)
				(type default)
			)
			(layer "B.SilkS")
		)
		(fp_rect
			(start 0.9652 1.778)
			(end -0.9652 -1.778)
			(stroke
				(width 0)
				(type default)
			)
			(fill no)
			(layer "B.CrtYd")
		)
		(fp_poly
			(pts
				(xy 0.9652 -1.778) (xy -0.9652 -1.778) (xy -0.9652 1.778) (xy 0.9652 1.778)
			)
			(stroke
				(width 0)
				(type default)
			)
			(fill no)
			(layer "B.Fab")
		)
		(pad "1" smd rect
			(at 0 -0.9652)
			(size 1.397 1.143)
			(layers "B.Cu" "B.Mask" "B.Paste")
			(net "P0V955_C")
		)
		(pad "2" smd rect
			(at 0 0.9652)
			(size 1.397 1.143)
			(layers "B.Cu" "B.Mask" "B.Paste")
			(net "GND")
		)
	)
	(footprint ""
		(layer "B.Cu")
		(at 120.53697 -106.426 180)
		(property "Reference" "SC1168"
			(at 0 0 0)
			(layer "B.SilkS")
			(hide yes)
			(effects
				(font
					(size 1.27 1.27)
				)
				(justify mirror)
			)
		)
		(property "Value" "SCD1U6D3V1KX-GP"
			(at 2.8321 -1.7399 180)
			(unlocked yes)
			(layer "B.Fab")
			(hide yes)
			(effects
				(font
					(size 1.016 1.016)
					(thickness 0.1524)
				)
				(justify mirror)
			)
		)
		(property "Device Type" "C0201H13"
			(at 2.8321 -3.2639 180)
			(unlocked yes)
			(layer "B.Fab")
			(hide yes)
			(effects
				(font
					(size 1.016 1.016)
					(thickness 0.1524)
				)
				(justify mirror)
			)
		)
		(duplicate_pad_numbers_are_jumpers no)
		(fp_rect
			(start 0.2794 0.6477)
			(end -0.2794 -0.6477)
			(stroke
				(width 0)
				(type default)
			)
			(fill no)
			(layer "B.CrtYd")
		)
		(fp_rect
			(start 0.2794 0.6477)
			(end -0.2794 -0.6477)
			(stroke
				(width 0)
				(type default)
			)
			(fill no)
			(layer "B.Fab")
		)
		(pad "1" smd custom
			(at 0 -0.2794)
			(size 0.0762 0.0762)
			(layers "B.Cu" "B.Mask" "B.Paste")
			(net "GB_VDDA")
			(options
				(clearance outline)
				(anchor circle)
			)
			(primitives
				(gr_poly
					(pts
						(arc
							(start 0.1524 0.127)
							(mid 0.137521 0.162921)
							(end 0.1016 0.1778)
						)
						(arc
							(start -0.1016 0.1778)
							(mid -0.137521 0.162921)
							(end -0.1524 0.127)
						)
						(arc
							(start -0.1524 -0.127)
							(mid -0.137521 -0.162921)
							(end -0.1016 -0.1778)
						)
						(arc
							(start 0.1016 -0.1778)
							(mid 0.137521 -0.162921)
							(end 0.1524 -0.127)
						)
					)
					(width 0)
					(fill yes)
				)
			)
		)
		(pad "2" smd custom
			(at 0 0.2794)
			(size 0.0762 0.0762)
			(layers "B.Cu" "B.Mask" "B.Paste")
			(net "GND")
			(options
				(clearance outline)
				(anchor circle)
			)
			(primitives
				(gr_poly
					(pts
						(arc
							(start 0.1524 0.127)
							(mid 0.137521 0.162921)
							(end 0.1016 0.1778)
						)
						(arc
							(start -0.1016 0.1778)
							(mid -0.137521 0.162921)
							(end -0.1524 0.127)
						)
						(arc
							(start -0.1524 -0.127)
							(mid -0.137521 -0.162921)
							(end -0.1016 -0.1778)
						)
						(arc
							(start 0.1016 -0.1778)
							(mid 0.137521 -0.162921)
							(end 0.1524 -0.127)
						)
					)
					(width 0)
					(fill yes)
				)
			)
		)
	)
	(footprint ""
		(layer "B.Cu")
		(at 295.656 -166.37)
		(property "Reference" "TP152"
			(at 0 0 0)
			(layer "B.SilkS")
			(hide yes)
			(effects
				(font
					(size 1.27 1.27)
				)
				(justify mirror)
			)
		)
		(property "Value" "TPAD28"
			(at -0.0127 -1.8034 0)
			(unlocked yes)
			(layer "B.Fab")
			(hide yes)
			(effects
				(font
					(size 1.016 1.016)
					(thickness 0.1524)
				)
				(justify mirror)
			)
		)
		(property "Device Type" "TPAD28"
			(at -0.0127 -3.3274 0)
			(unlocked yes)
			(layer "B.Fab")
			(hide yes)
			(effects
				(font
					(size 1.016 1.016)
					(thickness 0.1524)
				)
				(justify mirror)
			)
		)
		(duplicate_pad_numbers_are_jumpers no)
		(fp_poly
			(pts
				(arc
					(start 0.3556 0)
					(mid -0.3556 0)
					(end 0.3556 0)
				)
			)
			(stroke
				(width 0)
				(type default)
			)
			(fill no)
			(layer "B.CrtYd")
		)
		(fp_poly
			(pts
				(arc
					(start 0.6096 0)
					(mid -0.6096 0)
					(end 0.6096 0)
				)
			)
			(stroke
				(width 0)
				(type default)
			)
			(fill no)
			(layer "B.Fab")
		)
		(pad "1" smd circle
			(at 0 0 180)
			(size 0.7112 0.7112)
			(layers "B.Cu" "B.Mask" "B.Paste")
			(net "TP_BMC_GPIOU2")
		)
	)
	(footprint ""
		(layer "B.Cu")
		(at 92.564966 -33.401 -90)
		(property "Reference" "SC953"
			(at 0 0 90)
			(layer "B.SilkS")
			(hide yes)
			(effects
				(font
					(size 1.27 1.27)
				)
				(justify mirror)
			)
		)
		(property "Value" "SCD1U6D3V1KX-GP"
			(at 2.8321 -1.7399 270)
			(unlocked yes)
			(layer "B.Fab")
			(hide yes)
			(effects
				(font
					(size 1.016 1.016)
					(thickness 0.1524)
				)
				(justify mirror)
			)
		)
		(property "Device Type" "C0201H13"
			(at 2.8321 -3.2639 270)
			(unlocked yes)
			(layer "B.Fab")
			(hide yes)
			(effects
				(font
					(size 1.016 1.016)
					(thickness 0.1524)
				)
				(justify mirror)
			)
		)
		(duplicate_pad_numbers_are_jumpers no)
		(fp_rect
			(start 0.2794 0.6477)
			(end -0.2794 -0.6477)
			(stroke
				(width 0)
				(type default)
			)
			(fill no)
			(layer "B.CrtYd")
		)
		(fp_rect
			(start 0.2794 0.6477)
			(end -0.2794 -0.6477)
			(stroke
				(width 0)
				(type default)
			)
			(fill no)
			(layer "B.Fab")
		)
		(pad "1" smd custom
			(at 0 -0.2794 90)
			(size 0.0762 0.0762)
			(layers "B.Cu" "B.Mask" "B.Paste")
			(net "PCE_AVDD")
			(options
				(clearance outline)
				(anchor circle)
			)
			(primitives
				(gr_poly
					(pts
						(arc
							(start 0.1524 0.127)
							(mid 0.137521 0.162921)
							(end 0.1016 0.1778)
						)
						(arc
							(start -0.1016 0.1778)
							(mid -0.137521 0.162921)
							(end -0.1524 0.127)
						)
						(arc
							(start -0.1524 -0.127)
							(mid -0.137521 -0.162921)
							(end -0.1016 -0.1778)
						)
						(arc
							(start 0.1016 -0.1778)
							(mid 0.137521 -0.162921)
							(end 0.1524 -0.127)
						)
					)
					(width 0)
					(fill yes)
				)
			)
		)
		(pad "2" smd custom
			(at 0 0.2794 90)
			(size 0.0762 0.0762)
			(layers "B.Cu" "B.Mask" "B.Paste")
			(net "GND")
			(options
				(clearance outline)
				(anchor circle)
			)
			(primitives
				(gr_poly
					(pts
						(arc
							(start 0.1524 0.127)
							(mid 0.137521 0.162921)
							(end 0.1016 0.1778)
						)
						(arc
							(start -0.1016 0.1778)
							(mid -0.137521 0.162921)
							(end -0.1524 0.127)
						)
						(arc
							(start -0.1524 -0.127)
							(mid -0.137521 -0.162921)
							(end -0.1016 -0.1778)
						)
						(arc
							(start 0.1016 -0.1778)
							(mid 0.137521 -0.162921)
							(end 0.1524 -0.127)
						)
					)
					(width 0)
					(fill yes)
				)
			)
		)
	)
	(footprint ""
		(layer "B.Cu")
		(at 274.193 -182.753 90)
		(property "Reference" "R355"
			(at 0 0 90)
			(layer "B.SilkS")
			(hide yes)
			(effects
				(font
					(size 1.27 1.27)
				)
				(justify mirror)
			)
		)
		(property "Value" "3K3R2F-2-GP"
			(at -0.064008 -3.993896 90)
			(unlocked yes)
			(layer "B.Fab")
			(hide yes)
			(effects
				(font
					(size 1.016 1.016)
					(thickness 0.1524)
				)
				(justify mirror)
			)
		)
		(property "Device Type" "R402H16"
			(at -0.064008 -5.517896 90)
			(unlocked yes)
			(layer "B.Fab")
			(hide yes)
			(effects
				(font
					(size 1.016 1.016)
					(thickness 0.1524)
				)
				(justify mirror)
			)
		)
		(duplicate_pad_numbers_are_jumpers no)
		(fp_line
			(start 0.508 -0.9398)
			(end 0.508 0.9398)
			(stroke
				(width 0.1524)
				(type default)
			)
			(layer "B.SilkS")
		)
		(fp_line
			(start -0.508 -0.9398)
			(end 0.508 -0.9398)
			(stroke
				(width 0.1524)
				(type default)
			)
			(layer "B.SilkS")
		)
		(fp_rect
			(start 0.508 0.9398)
			(end -0.508 -0.9398)
			(stroke
				(width 0)
				(type default)
			)
			(fill no)
			(layer "B.CrtYd")
		)
		(fp_rect
			(start 0.508 0.9398)
			(end -0.508 -0.9398)
			(stroke
				(width 0)
				(type default)
			)
			(fill no)
			(layer "B.Fab")
		)
		(pad "1" smd custom
			(at 0 -0.4445 270)
			(size 0.1397 0.1397)
			(layers "B.Cu" "B.Mask" "B.Paste")
			(net "P3V3_STBY")
			(options
				(clearance outline)
				(anchor circle)
			)
			(primitives
				(gr_poly
					(pts
						(arc
							(start -0.1778 0.2794)
							(mid -0.249642 0.249642)
							(end -0.2794 0.1778)
						)
						(arc
							(start -0.2794 -0.1778)
							(mid -0.249642 -0.249642)
							(end -0.1778 -0.2794)
						)
						(arc
							(start 0.1778 -0.2794)
							(mid 0.249642 -0.249642)
							(end 0.2794 -0.1778)
						)
						(arc
							(start 0.2794 0.1778)
							(mid 0.249642 0.249642)
							(end 0.1778 0.2794)
						)
					)
					(width 0)
					(fill yes)
				)
			)
		)
		(pad "2" smd custom
			(at 0 0.4445 270)
			(size 0.1397 0.1397)
			(layers "B.Cu" "B.Mask" "B.Paste")
			(net "ROMA4")
			(options
				(clearance outline)
				(anchor circle)
			)
			(primitives
				(gr_poly
					(pts
						(arc
							(start -0.1778 0.2794)
							(mid -0.249642 0.249642)
							(end -0.2794 0.1778)
						)
						(arc
							(start -0.2794 -0.1778)
							(mid -0.249642 -0.249642)
							(end -0.1778 -0.2794)
						)
						(arc
							(start 0.1778 -0.2794)
							(mid 0.249642 -0.249642)
							(end 0.2794 -0.1778)
						)
						(arc
							(start 0.2794 0.1778)
							(mid 0.249642 0.249642)
							(end 0.1778 0.2794)
						)
					)
					(width 0)
					(fill yes)
				)
			)
		)
	)
	(footprint ""
		(layer "B.Cu")
		(at 49.73193 -79.682086)
		(property "Reference" "TP187"
			(at 0 0 0)
			(layer "B.SilkS")
			(hide yes)
			(effects
				(font
					(size 1.27 1.27)
				)
				(justify mirror)
			)
		)
		(property "Value" "TPAD32-GP"
			(at 0 -3.166364 0)
			(unlocked yes)
			(layer "B.Fab")
			(hide yes)
			(effects
				(font
					(size 1.016 1.016)
					(thickness 0.1524)
				)
				(justify mirror)
			)
		)
		(property "Device Type" "TPAD32"
			(at 0 -4.690618 0)
			(unlocked yes)
			(layer "B.Fab")
			(hide yes)
			(effects
				(font
					(size 1.016 1.016)
					(thickness 0.1524)
				)
				(justify mirror)
			)
		)
		(duplicate_pad_numbers_are_jumpers no)
		(fp_poly
			(pts
				(arc
					(start 0.4064 0)
					(mid -0.4064 0)
					(end 0.4064 0)
				)
			)
			(stroke
				(width 0)
				(type default)
			)
			(fill no)
			(layer "B.CrtYd")
		)
		(fp_poly
			(pts
				(arc
					(start 0.7112 0)
					(mid -0.7112 0)
					(end 0.7112 0)
				)
			)
			(stroke
				(width 0)
				(type default)
			)
			(fill no)
			(layer "B.Fab")
		)
		(pad "1" smd circle
			(at 0 0 180)
			(size 0.8128 0.8128)
			(layers "B.Cu" "B.Mask" "B.Paste")
			(net "INT_CONN_A_SB6")
		)
	)
	(footprint ""
		(layer "B.Cu")
		(at 199.898 -104.902)
		(property "Reference" "PR9018"
			(at 0 0 0)
			(layer "B.SilkS")
			(hide yes)
			(effects
				(font
					(size 1.27 1.27)
				)
				(justify mirror)
			)
		)
		(property "Value" "2KR2F-3-GP"
			(at -0.064008 -3.993896 0)
			(unlocked yes)
			(layer "B.Fab")
			(hide yes)
			(effects
				(font
					(size 1.016 1.016)
					(thickness 0.1524)
				)
				(justify mirror)
			)
		)
		(property "Device Type" "R402H16"
			(at -0.064008 -5.517896 0)
			(unlocked yes)
			(layer "B.Fab")
			(hide yes)
			(effects
				(font
					(size 1.016 1.016)
					(thickness 0.1524)
				)
				(justify mirror)
			)
		)
		(duplicate_pad_numbers_are_jumpers no)
		(fp_line
			(start -0.508 -0.9398)
			(end 0.508 -0.9398)
			(stroke
				(width 0.1524)
				(type default)
			)
			(layer "B.SilkS")
		)
		(fp_line
			(start 0.508 -0.9398)
			(end 0.508 0.9398)
			(stroke
				(width 0.1524)
				(type default)
			)
			(layer "B.SilkS")
		)
		(fp_rect
			(start 0.508 0.9398)
			(end -0.508 -0.9398)
			(stroke
				(width 0)
				(type default)
			)
			(fill no)
			(layer "B.CrtYd")
		)
		(fp_rect
			(start 0.508 0.9398)
			(end -0.508 -0.9398)
			(stroke
				(width 0)
				(type default)
			)
			(fill no)
			(layer "B.Fab")
		)
		(pad "1" smd custom
			(at 0 -0.4445 180)
			(size 0.1397 0.1397)
			(layers "B.Cu" "B.Mask" "B.Paste")
			(net "P1V5_E_SW")
			(options
				(clearance outline)
				(anchor circle)
			)
			(primitives
				(gr_poly
					(pts
						(arc
							(start -0.1778 0.2794)
							(mid -0.249642 0.249642)
							(end -0.2794 0.1778)
						)
						(arc
							(start -0.2794 -0.1778)
							(mid -0.249642 -0.249642)
							(end -0.1778 -0.2794)
						)
						(arc
							(start 0.1778 -0.2794)
							(mid 0.249642 -0.249642)
							(end 0.2794 -0.1778)
						)
						(arc
							(start 0.2794 0.1778)
							(mid 0.249642 0.249642)
							(end 0.1778 0.2794)
						)
					)
					(width 0)
					(fill yes)
				)
			)
		)
		(pad "2" smd custom
			(at 0 0.4445 180)
			(size 0.1397 0.1397)
			(layers "B.Cu" "B.Mask" "B.Paste")
			(net "P1V5_E_VFB_R")
			(options
				(clearance outline)
				(anchor circle)
			)
			(primitives
				(gr_poly
					(pts
						(arc
							(start -0.1778 0.2794)
							(mid -0.249642 0.249642)
							(end -0.2794 0.1778)
						)
						(arc
							(start -0.2794 -0.1778)
							(mid -0.249642 -0.249642)
							(end -0.1778 -0.2794)
						)
						(arc
							(start 0.1778 -0.2794)
							(mid 0.249642 -0.249642)
							(end 0.2794 -0.1778)
						)
						(arc
							(start 0.2794 0.1778)
							(mid 0.249642 0.249642)
							(end 0.1778 0.2794)
						)
					)
					(width 0)
					(fill yes)
				)
			)
		)
	)
)
